# S9S_MB_2U (Grand Teton) — schematic netlist excerpt (pin names and nets, part order shuffled) for the footprints in the layout excerpt that follows; sources: Cadence DE-HDL packaged netlist, KiCad conversion of 03242023_DA0F0TMBIJ0_F0T_Motherboard_J_brd_V01_OCP.brd

X17  TP_TDR_4P_FTS  TP_TDR_4P_DIP EMPTY  pkg TH  page 309
  S1  = TDR_DIFF_100_IN4_DP
  P1  = T1_GND
  P2  = T1_GND
  S2  = TDR_DIFF_100_IN4_DN

C2860  Q_CAP  1000PF 50V 5% X7R  pkg 0402  page 284 : A = PVCCIN_CPU1_EN_R ; B = GND

(kicad_pcb
	(version 20260206)
	(generator "pcbnew")
	(generator_version "10.0")
	(general
		(thickness 1.6)
		(legacy_teardrops no)
	)
	(paper "A4")
	(title_block
		(title "03242023_DA0F0TMBIJ0_F0T_Motherboard_J_brd_V01_OCP.brd")
		(comment 1 "Grand Teton / footprints 5030-5031 of 6105")
	)
	(layers
		(0 "F.Cu" signal "TOP")
		(4 "In1.Cu" signal "GND")
		(6 "In2.Cu" signal "IN1")
		(8 "In3.Cu" signal "GND1")
		(10 "In4.Cu" signal "IN2")
		(12 "In5.Cu" signal "GND2")
		(14 "In6.Cu" signal "IN3")
		(16 "In7.Cu" signal "GND3")
		(18 "In8.Cu" signal "VCC")
		(20 "In9.Cu" signal "VCC1")
		(22 "In10.Cu" signal "GND4")
		(24 "In11.Cu" signal "IN4")
		(26 "In12.Cu" signal "GND5")
		(28 "In13.Cu" signal "IN5")
		(30 "In14.Cu" signal "GND6")
		(32 "In15.Cu" signal "IN6")
		(34 "In16.Cu" signal "GND7")
		(2 "B.Cu" signal "BOTTOM")
		(9 "F.Adhes" user "F.Adhesive")
		(11 "B.Adhes" user "B.Adhesive")
		(13 "F.Paste" user "Package Geometry/Pastemask Top")
		(15 "B.Paste" user "Package Geometry/Pastemask Bottom")
		(5 "F.SilkS" user "Ref Des/Silkscreen Top")
		(7 "B.SilkS" user "Ref Des/Silkscreen Bottom")
		(1 "F.Mask" user "Board Geometry/Soldermask Top")
		(3 "B.Mask" user "Board Geometry/Soldermask Bottom")
		(17 "Dwgs.User" user "User.Drawings")
		(19 "Cmts.User" user "User.Comments")
		(21 "Eco1.User" user "User.Eco1")
		(23 "Eco2.User" user "User.Eco2")
		(25 "Edge.Cuts" user "Board Geometry/Outline")
		(27 "Margin" user)
		(31 "F.CrtYd" user "Package Geometry/Place Bound Top")
		(29 "B.CrtYd" user "Package Geometry/Place Bound Bottom")
		(35 "F.Fab" user "Ref Des/Assembly Top")
		(33 "B.Fab" user "Ref Des/Assembly Bottom")
	)
	(footprint ""
		(layer "B.Cu")
		(at 106.281474 -359.47985 180)
		(property "Reference" "C2860"
			(at 0 0 0)
			(layer "B.SilkS")
			(hide yes)
			(effects
				(font
					(size 1.27 1.27)
				)
				(justify mirror)
			)
		)
		(property "Value" ""
			(at 0 0 0)
			(layer "B.Fab")
			(effects
				(font
					(size 1.27 1.27)
				)
				(justify mirror)
			)
		)
		(duplicate_pad_numbers_are_jumpers no)
		(fp_line
			(start 0.7874 0.4064)
			(end 0.7874 -0.4064)
			(stroke
				(width 0.1524)
				(type default)
			)
			(layer "B.SilkS")
		)
		(fp_line
			(start 0.7874 -0.4064)
			(end -0.7874 -0.4064)
			(stroke
				(width 0.1524)
				(type default)
			)
			(layer "B.SilkS")
		)
		(fp_line
			(start -0.7874 0.4064)
			(end 0.7874 0.4064)
			(stroke
				(width 0.1524)
				(type default)
			)
			(layer "B.SilkS")
		)
		(fp_line
			(start -0.7874 -0.4064)
			(end -0.7874 0.4064)
			(stroke
				(width 0.1524)
				(type default)
			)
			(layer "B.SilkS")
		)
		(fp_line
			(start 0.67945 0.3048)
			(end 0.67945 -0.305054)
			(stroke
				(width 0.1)
				(type default)
			)
			(layer "B.Fab")
		)
		(fp_line
			(start 0.67945 -0.305054)
			(end 0.12065 -0.305054)
			(stroke
				(width 0.1)
				(type default)
			)
			(layer "B.Fab")
		)
		(fp_line
			(start 0.12065 0.3048)
			(end 0.67945 0.3048)
			(stroke
				(width 0.1)
				(type default)
			)
			(layer "B.Fab")
		)
		(fp_line
			(start 0.12065 0.2794)
			(end 0.12065 0.3048)
			(stroke
				(width 0.1)
				(type default)
			)
			(layer "B.Fab")
		)
		(fp_line
			(start 0.12065 -0.2794)
			(end -0.12065 -0.2794)
			(stroke
				(width 0.1)
				(type default)
			)
			(layer "B.Fab")
		)
		(fp_line
			(start 0.12065 -0.305054)
			(end 0.12065 -0.2794)
			(stroke
				(width 0.1)
				(type default)
			)
			(layer "B.Fab")
		)
		(fp_line
			(start -0.120396 0.3048)
			(end -0.120396 0.2794)
			(stroke
				(width 0.1)
				(type default)
			)
			(layer "B.Fab")
		)
		(fp_line
			(start -0.120396 0.2794)
			(end 0.12065 0.2794)
			(stroke
				(width 0.1)
				(type default)
			)
			(layer "B.Fab")
		)
		(fp_line
			(start -0.12065 -0.2794)
			(end -0.12065 -0.3048)
			(stroke
				(width 0.1)
				(type default)
			)
			(layer "B.Fab")
		)
		(fp_line
			(start -0.12065 -0.3048)
			(end -0.67945 -0.3048)
			(stroke
				(width 0.1)
				(type default)
			)
			(layer "B.Fab")
		)
		(fp_line
			(start -0.67945 0.3048)
			(end -0.120396 0.3048)
			(stroke
				(width 0.1)
				(type default)
			)
			(layer "B.Fab")
		)
		(fp_line
			(start -0.67945 -0.3048)
			(end -0.67945 0.3048)
			(stroke
				(width 0.1)
				(type default)
			)
			(layer "B.Fab")
		)
		(pad "1" smd circle
			(at 0.40005 0)
			(size 0 0)
			(layers "B.Cu" "B.Mask" "B.Paste")
			(net "PVCCIN_CPU1_EN_R")
		)
		(pad "2" smd circle
			(at -0.40005 0)
			(size 0 0)
			(layers "B.Cu" "B.Mask" "B.Paste")
			(net "GND")
		)
	)
	(footprint ""
		(layer "B.Cu")
		(at 514.718808 2.286 90)
		(property "Reference" "X17"
			(at 1.35128 3.208782 270)
			(unlocked yes)
			(layer "B.SilkS")
			(effects
				(font
					(size 0.7874 0.5842)
					(thickness 0.1524)
				)
				(justify left mirror)
			)
		)
		(property "Value" ""
			(at 0 0 90)
			(layer "B.Fab")
			(effects
				(font
					(size 1.27 1.27)
				)
				(justify mirror)
			)
		)
		(property "Device Type" "TP_TDR_4P_FTS_TH-TP_TDR_4P_DIPA"
			(at -1.30175 1.27 0)
			(unlocked yes)
			(layer "B.Fab")
			(hide yes)
			(effects
				(font
					(size 0.635 0.4064)
					(thickness 0.1524)
				)
				(justify mirror)
			)
		)
		(property "User Part Number" "N_A"
			(at -1.30175 1.27 0)
			(unlocked yes)
			(layer "Cmts.User")
			(hide yes)
			(effects
				(font
					(size 0.635 0.4064)
					(thickness 0.1524)
				)
				(justify mirror)
			)
		)
		(duplicate_pad_numbers_are_jumpers no)
		(fp_line
			(start 0 -1.27)
			(end 0 -0.635)
			(stroke
				(width 0.1524)
				(type default)
			)
			(layer "B.SilkS")
		)
		(fp_line
			(start -2.54 -1.27)
			(end 0 -1.27)
			(stroke
				(width 0.1524)
				(type default)
			)
			(layer "B.SilkS")
		)
		(fp_line
			(start -2.54 -1.1303)
			(end -2.54 -1.27)
			(stroke
				(width 0.1524)
				(type default)
			)
			(layer "B.SilkS")
		)
		(fp_line
			(start 0 0.635)
			(end 0 1.905)
			(stroke
				(width 0.1524)
				(type default)
			)
			(layer "B.SilkS")
		)
		(fp_line
			(start -2.54 1.4097)
			(end -2.54 1.1303)
			(stroke
				(width 0.1524)
				(type default)
			)
			(layer "B.SilkS")
		)
		(fp_line
			(start 0 3.175)
			(end 0 3.81)
			(stroke
				(width 0.1524)
				(type default)
			)
			(layer "B.SilkS")
		)
		(fp_line
			(start 0 3.81)
			(end -2.54 3.81)
			(stroke
				(width 0.1524)
				(type default)
			)
			(layer "B.SilkS")
		)
		(fp_line
			(start -2.54 3.81)
			(end -2.54 3.6703)
			(stroke
				(width 0.1524)
				(type default)
			)
			(layer "B.SilkS")
		)
		(fp_poly
			(pts
				(xy 2.285746 -0.762) (xy 2.285746 0.762) (xy 0.761746 0)
			)
			(stroke
				(width 0)
				(type default)
			)
			(fill yes)
			(layer "B.SilkS")
		)
		(fp_line
			(start 0 -1.27)
			(end 0 3.81)
			(stroke
				(width 0.1)
				(type default)
			)
			(layer "B.Fab")
		)
		(fp_line
			(start -2.54 -1.27)
			(end 0 -1.27)
			(stroke
				(width 0.1)
				(type default)
			)
			(layer "B.Fab")
		)
		(fp_line
			(start 0 3.81)
			(end -2.54 3.81)
			(stroke
				(width 0.1)
				(type default)
			)
			(layer "B.Fab")
		)
		(fp_line
			(start -2.54 3.81)
			(end -2.54 -1.27)
			(stroke
				(width 0.1)
				(type default)
			)
			(layer "B.Fab")
		)
		(fp_poly
			(pts
				(xy 0.761746 0) (xy 2.285746 -0.762) (xy 2.285746 0.762)
			)
			(stroke
				(width 0)
				(type default)
			)
			(fill yes)
			(layer "B.Fab")
		)
		(pad "1" thru_hole circle
			(at 0 0 270)
			(size 1.0033 1.0033)
			(drill 0.249936)
			(layers "*.Cu" "*.Mask")
			(remove_unused_layers no)
			(net "TDR_DIFF_100_IN4_DP")
			(clearance 0.10795)
			(padstack
				(mode front_inner_back)
				(layer "Inner"
					(shape circle)
					(size 0.8001 0.8001)
					(clearance 0.1524)
				)
				(layer "B.Cu"
					(shape circle)
					(size 1.0033 1.0033)
					(thermal_gap 0.10795)
					(clearance 0.10795)
				)
			)
		)
		(pad "2" thru_hole circle
			(at -2.54 0 270)
			(size 1.9939 1.9939)
			(drill 0.249936)
			(layers "*.Cu" "*.Mask")
			(remove_unused_layers no)
			(net "T1_GND")
			(clearance 0.10795)
			(padstack
				(mode front_inner_back)
				(layer "Inner"
					(shape circle)
					(size 0.8001 0.8001)
					(clearance 0.1524)
				)
				(layer "B.Cu"
					(shape circle)
					(size 1.9939 1.9939)
					(thermal_gap 0.10795)
					(clearance 0.10795)
				)
			)
		)
		(pad "3" thru_hole circle
			(at -2.54 2.54 270)
			(size 1.9939 1.9939)
			(drill 0.249936)
			(layers "*.Cu" "*.Mask")
			(remove_unused_layers no)
			(net "T1_GND")
			(clearance 0.10795)
			(padstack
				(mode front_inner_back)
				(layer "Inner"
					(shape circle)
					(size 0.8001 0.8001)
					(clearance 0.1524)
				)
				(layer "B.Cu"
					(shape circle)
					(size 1.9939 1.9939)
					(thermal_gap 0.10795)
					(clearance 0.10795)
				)
			)
		)
		(pad "4" thru_hole circle
			(at 0 2.54 270)
			(size 1.0033 1.0033)
			(drill 0.249936)
			(layers "*.Cu" "*.Mask")
			(remove_unused_layers no)
			(net "TDR_DIFF_100_IN4_DN")
			(clearance 0.10795)
			(padstack
				(mode front_inner_back)
				(layer "Inner"
					(shape circle)
					(size 0.8001 0.8001)
					(clearance 0.1524)
				)
				(layer "B.Cu"
					(shape circle)
					(size 1.0033 1.0033)
					(thermal_gap 0.10795)
					(clearance 0.10795)
				)
			)
		)
	)
)
